(kicad_pcb
	(version 20260206)
	(generator "pcbnew")
	(generator_version "10.0")
	(general
		(thickness 1.6)
		(legacy_teardrops no)
	)
	(paper "A4")
	(title_block
		(title "peb — Lightning_PEB_BRD.brd")
		(comment 1 "Lightning (Wiwynn / Facebook NVMe JBOF) / footprints 1312-1319 of 2563")
	)
	(layers
		(0 "F.Cu" signal "TOP")
		(4 "In1.Cu" signal "L2GND")
		(6 "In2.Cu" signal "L3")
		(8 "In3.Cu" signal "L4VCC")
		(10 "In4.Cu" signal "L5VCC")
		(12 "In5.Cu" signal "L6")
		(14 "In6.Cu" signal "L7GND")
		(2 "B.Cu" signal "BOTTOM")
		(9 "F.Adhes" user "F.Adhesive")
		(11 "B.Adhes" user "B.Adhesive")
		(13 "F.Paste" user "Package Geometry/Pastemask Top")
		(15 "B.Paste" user "Package Geometry/Pastemask Bottom")
		(5 "F.SilkS" user "Ref Des/Silkscreen Top")
		(7 "B.SilkS" user "Ref Des/Silkscreen Bottom")
		(1 "F.Mask" user "Board Geometry/Soldermask Top")
		(3 "B.Mask" user "Board Geometry/Soldermask Bottom")
		(17 "Dwgs.User" user "User.Drawings")
		(19 "Cmts.User" user "User.Comments")
		(21 "Eco1.User" user "User.Eco1")
		(23 "Eco2.User" user "User.Eco2")
		(25 "Edge.Cuts" user "Board Geometry/Outline")
		(27 "Margin" user)
		(31 "F.CrtYd" user "Package Geometry/Place Bound Top")
		(29 "B.CrtYd" user "Package Geometry/Place Bound Bottom")
		(35 "F.Fab" user "Ref Des/Assembly Top")
		(33 "B.Fab" user "Ref Des/Assembly Bottom")
	)
	(footprint ""
		(layer "F.Cu")
		(at 268.3256 -11.2776 -90)
		(property "Reference" "C241"
			(at 0 0 270)
			(layer "F.SilkS")
			(hide yes)
			(effects
				(font
					(size 1.27 1.27)
				)
			)
		)
		(property "Value" "SC1U10V2KX-4-GP"
			(at 1.1811 -2.7051 270)
			(unlocked yes)
			(layer "F.Fab")
			(hide yes)
			(effects
				(font
					(size 1.016 1.016)
					(thickness 0.1524)
				)
			)
		)
		(property "Device Type" "C402H22"
			(at 1.1811 -4.2291 270)
			(unlocked yes)
			(layer "F.Fab")
			(hide yes)
			(effects
				(font
					(size 1.016 1.016)
					(thickness 0.1524)
				)
			)
		)
		(duplicate_pad_numbers_are_jumpers no)
		(fp_rect
			(start -0.4318 0.9525)
			(end 0.4318 -0.9525)
			(stroke
				(width 0)
				(type default)
			)
			(fill no)
			(layer "F.CrtYd")
		)
		(fp_rect
			(start -0.4318 0.9525)
			(end 0.4318 -0.9525)
			(stroke
				(width 0)
				(type default)
			)
			(fill no)
			(layer "F.Fab")
		)
		(pad "1" smd custom
			(at 0 -0.4445 270)
			(size 0.1524 0.1524)
			(layers "F.Cu" "F.Mask" "F.Paste")
			(net "PM8536_RST#_LS_R")
			(options
				(clearance outline)
				(anchor circle)
			)
			(primitives
				(gr_poly
					(pts
						(arc
							(start 0.3048 -0.2032)
							(mid 0.275042 -0.275042)
							(end 0.2032 -0.3048)
						)
						(arc
							(start -0.2032 -0.3048)
							(mid -0.275042 -0.275042)
							(end -0.3048 -0.2032)
						)
						(arc
							(start -0.3048 0.2032)
							(mid -0.275042 0.275042)
							(end -0.2032 0.3048)
						)
						(arc
							(start 0.2032 0.3048)
							(mid 0.275042 0.275042)
							(end 0.3048 0.2032)
						)
					)
					(width 0)
					(fill yes)
				)
			)
		)
		(pad "2" smd custom
			(at 0 0.4445 270)
			(size 0.1524 0.1524)
			(layers "F.Cu" "F.Mask" "F.Paste")
			(net "GND")
			(options
				(clearance outline)
				(anchor circle)
			)
			(primitives
				(gr_poly
					(pts
						(arc
							(start 0.3048 -0.2032)
							(mid 0.275042 -0.275042)
							(end 0.2032 -0.3048)
						)
						(arc
							(start -0.2032 -0.3048)
							(mid -0.275042 -0.275042)
							(end -0.3048 -0.2032)
						)
						(arc
							(start -0.3048 0.2032)
							(mid -0.275042 0.275042)
							(end -0.2032 0.3048)
						)
						(arc
							(start 0.2032 0.3048)
							(mid 0.275042 0.275042)
							(end 0.3048 0.2032)
						)
					)
					(width 0)
					(fill yes)
				)
			)
		)
	)
	(footprint ""
		(layer "F.Cu")
		(at 205.3844 -24.0284 90)
		(property "Reference" "R2969"
			(at 0 0 90)
			(layer "F.SilkS")
			(hide yes)
			(effects
				(font
					(size 1.27 1.27)
				)
			)
		)
		(property "Value" "0R2J-2-GP"
			(at 0.064008 -3.993896 90)
			(unlocked yes)
			(layer "F.Fab")
			(hide yes)
			(effects
				(font
					(size 1.016 1.016)
					(thickness 0.1524)
				)
			)
		)
		(property "Device Type" "R402H16"
			(at 0.064008 -5.517896 90)
			(unlocked yes)
			(layer "F.Fab")
			(hide yes)
			(effects
				(font
					(size 1.016 1.016)
					(thickness 0.1524)
				)
			)
		)
		(duplicate_pad_numbers_are_jumpers no)
		(fp_line
			(start 0.508 -0.9398)
			(end -0.508 -0.9398)
			(stroke
				(width 0.1524)
				(type default)
			)
			(layer "F.SilkS")
		)
		(fp_line
			(start -0.508 -0.9398)
			(end -0.508 0.9398)
			(stroke
				(width 0.1524)
				(type default)
			)
			(layer "F.SilkS")
		)
		(fp_rect
			(start -0.508 0.9398)
			(end 0.508 -0.9398)
			(stroke
				(width 0)
				(type default)
			)
			(fill no)
			(layer "F.CrtYd")
		)
		(fp_rect
			(start -0.508 0.9398)
			(end 0.508 -0.9398)
			(stroke
				(width 0)
				(type default)
			)
			(fill no)
			(layer "F.Fab")
		)
		(pad "1" smd custom
			(at 0 -0.4445 90)
			(size 0.1397 0.1397)
			(layers "F.Cu" "F.Mask" "F.Paste")
			(net "U56_SCL")
			(options
				(clearance outline)
				(anchor circle)
			)
			(primitives
				(gr_poly
					(pts
						(arc
							(start -0.1778 -0.2794)
							(mid -0.249642 -0.249642)
							(end -0.2794 -0.1778)
						)
						(arc
							(start -0.2794 0.1778)
							(mid -0.249642 0.249642)
							(end -0.1778 0.2794)
						)
						(arc
							(start 0.1778 0.2794)
							(mid 0.249642 0.249642)
							(end 0.2794 0.1778)
						)
						(arc
							(start 0.2794 -0.1778)
							(mid 0.249642 -0.249642)
							(end 0.1778 -0.2794)
						)
					)
					(width 0)
					(fill yes)
				)
			)
		)
		(pad "2" smd custom
			(at 0 0.4445 90)
			(size 0.1397 0.1397)
			(layers "F.Cu" "F.Mask" "F.Paste")
			(net "BMC_I2C8_CLKBUF1_SCL")
			(options
				(clearance outline)
				(anchor circle)
			)
			(primitives
				(gr_poly
					(pts
						(arc
							(start -0.1778 -0.2794)
							(mid -0.249642 -0.249642)
							(end -0.2794 -0.1778)
						)
						(arc
							(start -0.2794 0.1778)
							(mid -0.249642 0.249642)
							(end -0.1778 0.2794)
						)
						(arc
							(start 0.1778 0.2794)
							(mid 0.249642 0.249642)
							(end 0.2794 0.1778)
						)
						(arc
							(start 0.2794 -0.1778)
							(mid 0.249642 -0.249642)
							(end 0.1778 -0.2794)
						)
					)
					(width 0)
					(fill yes)
				)
			)
		)
	)
	(footprint ""
		(layer "F.Cu")
		(at 177.485802 -71.071232 -90)
		(property "Reference" "PG32"
			(at 0 0 270)
			(layer "F.SilkS")
			(hide yes)
			(effects
				(font
					(size 1.27 1.27)
				)
			)
		)
		(property "Value" "GAP-CLOSE-PWR-3-GP"
			(at 0.0254 -6.5786 270)
			(unlocked yes)
			(layer "F.Fab")
			(hide yes)
			(effects
				(font
					(size 1.016 1.016)
					(thickness 0.1524)
				)
			)
		)
		(property "Device Type" "GAP-CLOSE-PWR-3"
			(at 0.0254 -8.255 270)
			(unlocked yes)
			(layer "F.Fab")
			(hide yes)
			(effects
				(font
					(size 1.016 1.016)
					(thickness 0.1524)
				)
			)
		)
		(duplicate_pad_numbers_are_jumpers no)
		(fp_rect
			(start -0.7112 0.4572)
			(end 0.7112 -0.4572)
			(stroke
				(width 0)
				(type default)
			)
			(fill no)
			(layer "F.CrtYd")
		)
		(fp_poly
			(pts
				(xy -0.7112 -0.4572) (xy 0.7112 -0.4572) (xy 0.7112 0.4572) (xy -0.7112 0.4572)
			)
			(stroke
				(width 0)
				(type default)
			)
			(fill no)
			(layer "F.Fab")
		)
		(pad "1" smd rect
			(at -0.3048 0 270)
			(size 0.6604 0.762)
			(layers "F.Cu" "F.Mask" "F.Paste")
			(net "DUT_AVD_TX")
		)
		(pad "2" smd rect
			(at 0.3048 0 270)
			(size 0.6604 0.762)
			(layers "F.Cu" "F.Mask" "F.Paste")
			(net "P0V9")
		)
	)
	(footprint ""
		(layer "F.Cu")
		(at 327.787 -86.487)
		(property "Reference" "R4170"
			(at 0 0 0)
			(layer "F.SilkS")
			(hide yes)
			(effects
				(font
					(size 1.27 1.27)
				)
			)
		)
		(property "Value" "4K7R2F-GP"
			(at 0.064008 -3.993896 0)
			(unlocked yes)
			(layer "F.Fab")
			(hide yes)
			(effects
				(font
					(size 1.016 1.016)
					(thickness 0.1524)
				)
			)
		)
		(property "Device Type" "R402H16"
			(at 0.064008 -5.517896 0)
			(unlocked yes)
			(layer "F.Fab")
			(hide yes)
			(effects
				(font
					(size 1.016 1.016)
					(thickness 0.1524)
				)
			)
		)
		(duplicate_pad_numbers_are_jumpers no)
		(fp_line
			(start -0.508 -0.9398)
			(end -0.508 0.9398)
			(stroke
				(width 0.1524)
				(type default)
			)
			(layer "F.SilkS")
		)
		(fp_line
			(start 0.508 -0.9398)
			(end -0.508 -0.9398)
			(stroke
				(width 0.1524)
				(type default)
			)
			(layer "F.SilkS")
		)
		(fp_rect
			(start -0.508 0.9398)
			(end 0.508 -0.9398)
			(stroke
				(width 0)
				(type default)
			)
			(fill no)
			(layer "F.CrtYd")
		)
		(fp_rect
			(start -0.508 0.9398)
			(end 0.508 -0.9398)
			(stroke
				(width 0)
				(type default)
			)
			(fill no)
			(layer "F.Fab")
		)
		(pad "1" smd custom
			(at 0 -0.4445)
			(size 0.1397 0.1397)
			(layers "F.Cu" "F.Mask" "F.Paste")
			(net "UPLINK5")
			(options
				(clearance outline)
				(anchor circle)
			)
			(primitives
				(gr_poly
					(pts
						(arc
							(start -0.1778 -0.2794)
							(mid -0.249642 -0.249642)
							(end -0.2794 -0.1778)
						)
						(arc
							(start -0.2794 0.1778)
							(mid -0.249642 0.249642)
							(end -0.1778 0.2794)
						)
						(arc
							(start 0.1778 0.2794)
							(mid 0.249642 0.249642)
							(end 0.2794 0.1778)
						)
						(arc
							(start 0.2794 -0.1778)
							(mid 0.249642 -0.249642)
							(end 0.1778 -0.2794)
						)
					)
					(width 0)
					(fill yes)
				)
			)
		)
		(pad "2" smd custom
			(at 0 0.4445)
			(size 0.1397 0.1397)
			(layers "F.Cu" "F.Mask" "F.Paste")
			(net "P3V3_STBY")
			(options
				(clearance outline)
				(anchor circle)
			)
			(primitives
				(gr_poly
					(pts
						(arc
							(start -0.1778 -0.2794)
							(mid -0.249642 -0.249642)
							(end -0.2794 -0.1778)
						)
						(arc
							(start -0.2794 0.1778)
							(mid -0.249642 0.249642)
							(end -0.1778 0.2794)
						)
						(arc
							(start 0.1778 0.2794)
							(mid 0.249642 0.249642)
							(end 0.2794 0.1778)
						)
						(arc
							(start 0.2794 -0.1778)
							(mid 0.249642 -0.249642)
							(end 0.1778 -0.2794)
						)
					)
					(width 0)
					(fill yes)
				)
			)
		)
	)
	(footprint ""
		(layer "F.Cu")
		(at 217.04554 -31.15056)
		(property "Reference" "TP311"
			(at 0 0 0)
			(layer "F.SilkS")
			(hide yes)
			(effects
				(font
					(size 1.27 1.27)
				)
			)
		)
		(property "Value" "TPAD28-2-GP"
			(at -0.0127 -1.6637 0)
			(unlocked yes)
			(layer "F.Fab")
			(hide yes)
			(effects
				(font
					(size 1.016 1.016)
					(thickness 0.1524)
				)
			)
		)
		(property "Device Type" "TPAD28"
			(at -0.0127 -3.1877 0)
			(unlocked yes)
			(layer "F.Fab")
			(hide yes)
			(effects
				(font
					(size 1.016 1.016)
					(thickness 0.1524)
				)
			)
		)
		(duplicate_pad_numbers_are_jumpers no)
		(fp_poly
			(pts
				(arc
					(start 0.3556 0)
					(mid -0.3556 0)
					(end 0.3556 0)
				)
			)
			(stroke
				(width 0)
				(type default)
			)
			(fill no)
			(layer "F.CrtYd")
		)
		(fp_poly
			(pts
				(arc
					(start 0.6096 0)
					(mid -0.6096 0)
					(end 0.6096 0)
				)
			)
			(stroke
				(width 0)
				(type default)
			)
			(fill no)
			(layer "F.Fab")
		)
		(pad "1" smd circle
			(at 0 0)
			(size 0.7112 0.7112)
			(layers "F.Cu" "F.Mask" "F.Paste")
			(net "LBI_DATA14_R")
		)
	)
	(footprint ""
		(layer "F.Cu")
		(at 134.292086 -74.468482)
		(property "Reference" "R957"
			(at 0 0 0)
			(layer "F.SilkS")
			(hide yes)
			(effects
				(font
					(size 1.27 1.27)
				)
			)
		)
		(property "Value" "33R2J-2-GP"
			(at 0.064008 -3.993896 0)
			(unlocked yes)
			(layer "F.Fab")
			(hide yes)
			(effects
				(font
					(size 1.016 1.016)
					(thickness 0.1524)
				)
			)
		)
		(property "Device Type" "R402H16"
			(at 0.064008 -5.517896 0)
			(unlocked yes)
			(layer "F.Fab")
			(hide yes)
			(effects
				(font
					(size 1.016 1.016)
					(thickness 0.1524)
				)
			)
		)
		(duplicate_pad_numbers_are_jumpers no)
		(fp_line
			(start -0.508 -0.9398)
			(end -0.508 0.9398)
			(stroke
				(width 0.1524)
				(type default)
			)
			(layer "F.SilkS")
		)
		(fp_line
			(start 0.508 -0.9398)
			(end -0.508 -0.9398)
			(stroke
				(width 0.1524)
				(type default)
			)
			(layer "F.SilkS")
		)
		(fp_rect
			(start -0.508 0.9398)
			(end 0.508 -0.9398)
			(stroke
				(width 0)
				(type default)
			)
			(fill no)
			(layer "F.CrtYd")
		)
		(fp_rect
			(start -0.508 0.9398)
			(end 0.508 -0.9398)
			(stroke
				(width 0)
				(type default)
			)
			(fill no)
			(layer "F.Fab")
		)
		(pad "1" smd custom
			(at 0 -0.4445)
			(size 0.1397 0.1397)
			(layers "F.Cu" "F.Mask" "F.Paste")
			(net "SPI_DATA0_3_R")
			(options
				(clearance outline)
				(anchor circle)
			)
			(primitives
				(gr_poly
					(pts
						(arc
							(start -0.1778 -0.2794)
							(mid -0.249642 -0.249642)
							(end -0.2794 -0.1778)
						)
						(arc
							(start -0.2794 0.1778)
							(mid -0.249642 0.249642)
							(end -0.1778 0.2794)
						)
						(arc
							(start 0.1778 0.2794)
							(mid 0.249642 0.249642)
							(end 0.2794 0.1778)
						)
						(arc
							(start 0.2794 -0.1778)
							(mid 0.249642 -0.249642)
							(end 0.1778 -0.2794)
						)
					)
					(width 0)
					(fill yes)
				)
			)
		)
		(pad "2" smd custom
			(at 0 0.4445)
			(size 0.1397 0.1397)
			(layers "F.Cu" "F.Mask" "F.Paste")
			(net "SPI_DATA0_3")
			(options
				(clearance outline)
				(anchor circle)
			)
			(primitives
				(gr_poly
					(pts
						(arc
							(start -0.1778 -0.2794)
							(mid -0.249642 -0.249642)
							(end -0.2794 -0.1778)
						)
						(arc
							(start -0.2794 0.1778)
							(mid -0.249642 0.249642)
							(end -0.1778 0.2794)
						)
						(arc
							(start 0.1778 0.2794)
							(mid 0.249642 0.249642)
							(end 0.2794 0.1778)
						)
						(arc
							(start 0.2794 -0.1778)
							(mid 0.249642 -0.249642)
							(end 0.1778 -0.2794)
						)
					)
					(width 0)
					(fill yes)
				)
			)
		)
	)
	(footprint ""
		(layer "F.Cu")
		(at 323.469 -99.568)
		(property "Reference" "R513"
			(at 0 0 0)
			(layer "F.SilkS")
			(hide yes)
			(effects
				(font
					(size 1.27 1.27)
				)
			)
		)
		(property "Value" "10KR2F-2-GP"
			(at 0.064008 -3.993896 0)
			(unlocked yes)
			(layer "F.Fab")
			(hide yes)
			(effects
				(font
					(size 1.016 1.016)
					(thickness 0.1524)
				)
			)
		)
		(property "Device Type" "R402H16"
			(at 0.064008 -5.517896 0)
			(unlocked yes)
			(layer "F.Fab")
			(hide yes)
			(effects
				(font
					(size 1.016 1.016)
					(thickness 0.1524)
				)
			)
		)
		(duplicate_pad_numbers_are_jumpers no)
		(fp_line
			(start -0.508 -0.9398)
			(end -0.508 0.9398)
			(stroke
				(width 0.1524)
				(type default)
			)
			(layer "F.SilkS")
		)
		(fp_line
			(start 0.508 -0.9398)
			(end -0.508 -0.9398)
			(stroke
				(width 0.1524)
				(type default)
			)
			(layer "F.SilkS")
		)
		(fp_rect
			(start -0.508 0.9398)
			(end 0.508 -0.9398)
			(stroke
				(width 0)
				(type default)
			)
			(fill no)
			(layer "F.CrtYd")
		)
		(fp_rect
			(start -0.508 0.9398)
			(end 0.508 -0.9398)
			(stroke
				(width 0)
				(type default)
			)
			(fill no)
			(layer "F.Fab")
		)
		(pad "1" smd custom
			(at 0 -0.4445)
			(size 0.1397 0.1397)
			(layers "F.Cu" "F.Mask" "F.Paste")
			(net "GND")
			(options
				(clearance outline)
				(anchor circle)
			)
			(primitives
				(gr_poly
					(pts
						(arc
							(start -0.1778 -0.2794)
							(mid -0.249642 -0.249642)
							(end -0.2794 -0.1778)
						)
						(arc
							(start -0.2794 0.1778)
							(mid -0.249642 0.249642)
							(end -0.1778 0.2794)
						)
						(arc
							(start 0.1778 0.2794)
							(mid 0.249642 0.249642)
							(end 0.2794 0.1778)
						)
						(arc
							(start 0.2794 -0.1778)
							(mid 0.249642 -0.249642)
							(end 0.1778 -0.2794)
						)
					)
					(width 0)
					(fill yes)
				)
			)
		)
		(pad "2" smd custom
			(at 0 0.4445)
			(size 0.1397 0.1397)
			(layers "F.Cu" "F.Mask" "F.Paste")
			(net "IOEXP_PMC1_AD0")
			(options
				(clearance outline)
				(anchor circle)
			)
			(primitives
				(gr_poly
					(pts
						(arc
							(start -0.1778 -0.2794)
							(mid -0.249642 -0.249642)
							(end -0.2794 -0.1778)
						)
						(arc
							(start -0.2794 0.1778)
							(mid -0.249642 0.249642)
							(end -0.1778 0.2794)
						)
						(arc
							(start 0.1778 0.2794)
							(mid 0.249642 0.249642)
							(end 0.2794 0.1778)
						)
						(arc
							(start 0.2794 -0.1778)
							(mid 0.249642 -0.249642)
							(end 0.1778 -0.2794)
						)
					)
					(width 0)
					(fill yes)
				)
			)
		)
	)
	(footprint ""
		(layer "F.Cu")
		(at 222.25 -23.241 180)
		(property "Reference" "R3723"
			(at 0 0 180)
			(layer "F.SilkS")
			(hide yes)
			(effects
				(font
					(size 1.27 1.27)
				)
			)
		)
		(property "Value" "4K7R2F-GP"
			(at 0.064008 -3.993896 180)
			(unlocked yes)
			(layer "F.Fab")
			(hide yes)
			(effects
				(font
					(size 1.016 1.016)
					(thickness 0.1524)
				)
			)
		)
		(property "Device Type" "R402H16"
			(at 0.064008 -5.517896 180)
			(unlocked yes)
			(layer "F.Fab")
			(hide yes)
			(effects
				(font
					(size 1.016 1.016)
					(thickness 0.1524)
				)
			)
		)
		(duplicate_pad_numbers_are_jumpers no)
		(fp_line
			(start 0.508 -0.9398)
			(end -0.508 -0.9398)
			(stroke
				(width 0.1524)
				(type default)
			)
			(layer "F.SilkS")
		)
		(fp_line
			(start -0.508 -0.9398)
			(end -0.508 0.9398)
			(stroke
				(width 0.1524)
				(type default)
			)
			(layer "F.SilkS")
		)
		(fp_rect
			(start -0.508 0.9398)
			(end 0.508 -0.9398)
			(stroke
				(width 0)
				(type default)
			)
			(fill no)
			(layer "F.CrtYd")
		)
		(fp_rect
			(start -0.508 0.9398)
			(end 0.508 -0.9398)
			(stroke
				(width 0)
				(type default)
			)
			(fill no)
			(layer "F.Fab")
		)
		(pad "1" smd custom
			(at 0 -0.4445 180)
			(size 0.1397 0.1397)
			(layers "F.Cu" "F.Mask" "F.Paste")
			(net "HOST8_RST_N_LS")
			(options
				(clearance outline)
				(anchor circle)
			)
			(primitives
				(gr_poly
					(pts
						(arc
							(start -0.1778 -0.2794)
							(mid -0.249642 -0.249642)
							(end -0.2794 -0.1778)
						)
						(arc
							(start -0.2794 0.1778)
							(mid -0.249642 0.249642)
							(end -0.1778 0.2794)
						)
						(arc
							(start 0.1778 0.2794)
							(mid 0.249642 0.249642)
							(end 0.2794 0.1778)
						)
						(arc
							(start 0.2794 -0.1778)
							(mid 0.249642 -0.249642)
							(end 0.1778 -0.2794)
						)
					)
					(width 0)
					(fill yes)
				)
			)
		)
		(pad "2" smd custom
			(at 0 0.4445 180)
			(size 0.1397 0.1397)
			(layers "F.Cu" "F.Mask" "F.Paste")
			(net "GND")
			(options
				(clearance outline)
				(anchor circle)
			)
			(primitives
				(gr_poly
					(pts
						(arc
							(start -0.1778 -0.2794)
							(mid -0.249642 -0.249642)
							(end -0.2794 -0.1778)
						)
						(arc
							(start -0.2794 0.1778)
							(mid -0.249642 0.249642)
							(end -0.1778 0.2794)
						)
						(arc
							(start 0.1778 0.2794)
							(mid 0.249642 0.249642)
							(end 0.2794 0.1778)
						)
						(arc
							(start 0.2794 -0.1778)
							(mid 0.249642 -0.249642)
							(end 0.1778 -0.2794)
						)
					)
					(width 0)
					(fill yes)
				)
			)
		)
	)
)
